(kicad_pcb
	(version 20260206)
	(generator "pcbnew")
	(generator_version "10.0")
	(general
		(thickness 0.77096)
		(legacy_teardrops no)
	)
	(paper "A4")
	(title_block
		(title "gnss-m2-neo-m9n — M2_NEO-M9N_MODULE.PcbDoc")
		(comment 1 "Time Appliance Project (Time Card) / footprints 33-36 of 40")
	)
	(layers
		(0 "F.Cu" signal "L01-Top Layer")
		(4 "In1.Cu" signal "L02-Inner Layer")
		(6 "In2.Cu" signal "L03-Inner Layer")
		(2 "B.Cu" signal "L04-Bottom Layer")
		(9 "F.Adhes" user "F.Adhesive")
		(11 "B.Adhes" user "B.Adhesive")
		(13 "F.Paste" user "Top Paste")
		(15 "B.Paste" user "Bottom Paste")
		(5 "F.SilkS" user "Top Overlay")
		(7 "B.SilkS" user "Bottom Overlay")
		(1 "F.Mask" user "Top Solder")
		(3 "B.Mask" user "Bottom Solder")
		(17 "Dwgs.User" user "User.Drawings")
		(19 "Cmts.User" user "User.Comments")
		(21 "Eco1.User" user "User.Eco1")
		(23 "Eco2.User" user "User.Eco2")
		(25 "Edge.Cuts" user)
		(27 "Margin" user)
		(31 "F.CrtYd" user "Top Courtyard")
		(29 "B.CrtYd" user "Bottom Courtyard")
		(35 "F.Fab" user "Top Component Outline")
		(33 "B.Fab" user "Bottom Component Outline 2")
	)
	(footprint "M2_Library:OCPTAP M2 FINGERS"
		(locked yes)
		(layer "F.Cu")
		(at 157.751105 124.7286)
		(property "Reference" "J1"
			(at -0.741195 -2.202557 0)
			(unlocked yes)
			(layer "F.SilkS")
			(effects
				(font
					(size 0.635 0.635)
					(thickness 0.1778)
				)
			)
		)
		(property "Value" "OCPTAP_M2_FINGERS"
			(at 7.908735 8.542283 0)
			(unlocked yes)
			(layer "F.SilkS")
			(hide yes)
			(effects
				(font
					(size 0.635 0.635)
					(thickness 0.1778)
				)
			)
		)
		(sheetname "02-M2_GoldFingers")
		(sheetfile "02-M2_GoldFingers.kicad_sch")
		(duplicate_pad_numbers_are_jumpers no)
		(fp_text user "75"
			(at -18.81125 -1.625 270)
			(unlocked yes)
			(layer "F.SilkS")
			(effects
				(font
					(size 0.5 0.5)
					(thickness 0.1)
				)
				(justify left bottom mirror)
			)
		)
		(fp_text user "21"
			(at -5.13625 -1.55001 270)
			(unlocked yes)
			(layer "F.SilkS")
			(effects
				(font
					(size 0.5 0.5)
					(thickness 0.1)
				)
				(justify left bottom mirror)
			)
		)
		(fp_text user "11"
			(at -2.81125 -1.50002 270)
			(unlocked yes)
			(layer "F.SilkS")
			(effects
				(font
					(size 0.5 0.5)
					(thickness 0.1)
				)
				(justify left bottom mirror)
			)
		)
		(fp_text user "1"
			(at -0.20525 -1.475 270)
			(unlocked yes)
			(layer "F.SilkS")
			(effects
				(font
					(size 0.5 0.5)
					(thickness 0.1)
				)
				(justify left bottom mirror)
			)
		)
		(fp_text user "74"
			(at -18.61125 -1.625 270)
			(unlocked yes)
			(layer "B.SilkS")
			(effects
				(font
					(size 0.5 0.5)
					(thickness 0.1)
				)
				(justify left bottom mirror)
			)
		)
		(fp_text user "20"
			(at -5.21125 -1.425 270)
			(unlocked yes)
			(layer "B.SilkS")
			(effects
				(font
					(size 0.5 0.5)
					(thickness 0.1)
				)
				(justify left bottom mirror)
			)
		)
		(fp_text user "10"
			(at -2.61125 -1.525 270)
			(unlocked yes)
			(layer "B.SilkS")
			(effects
				(font
					(size 0.5 0.5)
					(thickness 0.1)
				)
				(justify left bottom mirror)
			)
		)
		(fp_text user "2"
			(at -0.27841 -1.725 270)
			(unlocked yes)
			(layer "B.SilkS")
			(effects
				(font
					(size 0.5 0.5)
					(thickness 0.1)
				)
				(justify left bottom mirror)
			)
		)
		(pad "1" smd rect
			(at 0 0)
			(size 0.35 1.45)
			(layers "F.Cu" "F.Mask" "F.Paste")
		)
		(pad "2" smd rect
			(at -0.244 -0.25)
			(size 0.35 1.95)
			(layers "B.Cu" "B.Mask" "B.Paste")
			(net "+3V3")
		)
		(pad "3" smd rect
			(at -0.5 0)
			(size 0.35 1.45)
			(layers "F.Cu" "F.Mask" "F.Paste")
			(net "GND")
		)
		(pad "4" smd rect
			(at -0.744 -0.25)
			(size 0.35 1.95)
			(layers "B.Cu" "B.Mask" "B.Paste")
			(net "+3V3")
		)
		(pad "5" smd rect
			(at -1 0)
			(size 0.35 1.45)
			(layers "F.Cu" "F.Mask" "F.Paste")
			(net "GND")
		)
		(pad "6" smd rect
			(at -1.244 -0.25)
			(size 0.35 1.95)
			(layers "B.Cu" "B.Mask" "B.Paste")
		)
		(pad "7" smd rect
			(at -1.5 0)
			(size 0.35 1.45)
			(layers "F.Cu" "F.Mask" "F.Paste")
			(net "USB_DP")
		)
		(pad "8" smd rect
			(at -1.744 -0.25)
			(size 0.35 1.95)
			(layers "B.Cu" "B.Mask" "B.Paste")
		)
		(pad "9" smd rect
			(at -2 0)
			(size 0.35 1.45)
			(layers "F.Cu" "F.Mask" "F.Paste")
			(net "USB_DM")
		)
		(pad "10" smd rect
			(at -2.244 -0.25)
			(size 0.35 1.95)
			(layers "B.Cu" "B.Mask" "B.Paste")
		)
		(pad "11" smd rect
			(at -2.5 0)
			(size 0.35 1.45)
			(layers "F.Cu" "F.Mask" "F.Paste")
			(net "GND")
		)
		(pad "20" smd rect
			(at -4.744 -0.25)
			(size 0.35 1.95)
			(layers "B.Cu" "B.Mask" "B.Paste")
		)
		(pad "21" smd rect
			(at -5 0)
			(size 0.35 1.45)
			(layers "F.Cu" "F.Mask" "F.Paste")
			(net "GND")
		)
		(pad "22" smd rect
			(at -5.244 -0.25)
			(size 0.35 1.95)
			(layers "B.Cu" "B.Mask" "B.Paste")
		)
		(pad "23" smd rect
			(at -5.5 0)
			(size 0.35 1.45)
			(layers "F.Cu" "F.Mask" "F.Paste")
		)
		(pad "24" smd rect
			(at -5.744 -0.25)
			(size 0.35 1.95)
			(layers "B.Cu" "B.Mask" "B.Paste")
		)
		(pad "25" smd rect
			(at -6 0)
			(size 0.35 1.45)
			(layers "F.Cu" "F.Mask" "F.Paste")
		)
		(pad "26" smd rect
			(at -6.244 -0.25)
			(size 0.35 1.95)
			(layers "B.Cu" "B.Mask" "B.Paste")
		)
		(pad "27" smd rect
			(at -6.5 0)
			(size 0.35 1.45)
			(layers "F.Cu" "F.Mask" "F.Paste")
			(net "GND")
		)
		(pad "28" smd rect
			(at -6.744 -0.25)
			(size 0.35 1.95)
			(layers "B.Cu" "B.Mask" "B.Paste")
		)
		(pad "29" smd rect
			(at -7 0)
			(size 0.35 1.45)
			(layers "F.Cu" "F.Mask" "F.Paste")
		)
		(pad "30" smd rect
			(at -7.244 -0.25)
			(size 0.35 1.95)
			(layers "B.Cu" "B.Mask" "B.Paste")
		)
		(pad "31" smd rect
			(at -7.5 0)
			(size 0.35 1.45)
			(layers "F.Cu" "F.Mask" "F.Paste")
		)
		(pad "32" smd rect
			(at -7.744 -0.25)
			(size 0.35 1.95)
			(layers "B.Cu" "B.Mask" "B.Paste")
		)
		(pad "33" smd rect
			(at -8 0)
			(size 0.35 1.45)
			(layers "F.Cu" "F.Mask" "F.Paste")
			(net "GND")
		)
		(pad "34" smd rect
			(at -8.244 -0.25)
			(size 0.35 1.95)
			(layers "B.Cu" "B.Mask" "B.Paste")
		)
		(pad "35" smd rect
			(at -8.5 0)
			(size 0.35 1.45)
			(layers "F.Cu" "F.Mask" "F.Paste")
			(net "NetJ1_35")
		)
		(pad "36" smd rect
			(at -8.744 -0.25)
			(size 0.35 1.95)
			(layers "B.Cu" "B.Mask" "B.Paste")
		)
		(pad "37" smd rect
			(at -9 0)
			(size 0.35 1.45)
			(layers "F.Cu" "F.Mask" "F.Paste")
		)
		(pad "38" smd rect
			(at -9.244 -0.25)
			(size 0.35 1.95)
			(layers "B.Cu" "B.Mask" "B.Paste")
		)
		(pad "39" smd rect
			(at -9.5 0)
			(size 0.35 1.45)
			(layers "F.Cu" "F.Mask" "F.Paste")
			(net "GND")
		)
		(pad "40" smd rect
			(at -9.744 -0.25)
			(size 0.35 1.95)
			(layers "B.Cu" "B.Mask" "B.Paste")
			(net "SCL")
		)
		(pad "41" smd rect
			(at -10 0)
			(size 0.35 1.45)
			(layers "F.Cu" "F.Mask" "F.Paste")
		)
		(pad "42" smd rect
			(at -10.244 -0.25)
			(size 0.35 1.95)
			(layers "B.Cu" "B.Mask" "B.Paste")
			(net "SDA")
		)
		(pad "43" smd rect
			(at -10.5 0)
			(size 0.35 1.45)
			(layers "F.Cu" "F.Mask" "F.Paste")
		)
		(pad "44" smd rect
			(at -10.744 -0.25)
			(size 0.35 1.95)
			(layers "B.Cu" "B.Mask" "B.Paste")
		)
		(pad "45" smd rect
			(at -11 0)
			(size 0.35 1.45)
			(layers "F.Cu" "F.Mask" "F.Paste")
			(net "GND")
		)
		(pad "46" smd rect
			(at -11.244 -0.25)
			(size 0.35 1.95)
			(layers "B.Cu" "B.Mask" "B.Paste")
			(net "NetJ1_46")
		)
		(pad "47" smd rect
			(at -11.5 0)
			(size 0.35 1.45)
			(layers "F.Cu" "F.Mask" "F.Paste")
		)
		(pad "48" smd rect
			(at -11.744 -0.25)
			(size 0.35 1.95)
			(layers "B.Cu" "B.Mask" "B.Paste")
		)
		(pad "49" smd rect
			(at -12 0)
			(size 0.35 1.45)
			(layers "F.Cu" "F.Mask" "F.Paste")
		)
		(pad "50" smd rect
			(at -12.244 -0.25)
			(size 0.35 1.95)
			(layers "B.Cu" "B.Mask" "B.Paste")
			(net "NetJ1_50")
		)
		(pad "51" smd rect
			(at -12.5 0)
			(size 0.35 1.45)
			(layers "F.Cu" "F.Mask" "F.Paste")
			(net "GND")
		)
		(pad "52" smd rect
			(at -12.744 -0.25)
			(size 0.35 1.95)
			(layers "B.Cu" "B.Mask" "B.Paste")
		)
		(pad "53" smd rect
			(at -13 0)
			(size 0.35 1.45)
			(layers "F.Cu" "F.Mask" "F.Paste")
		)
		(pad "54" smd rect
			(at -13.244 -0.25)
			(size 0.35 1.95)
			(layers "B.Cu" "B.Mask" "B.Paste")
		)
		(pad "55" smd rect
			(at -13.5 0)
			(size 0.35 1.45)
			(layers "F.Cu" "F.Mask" "F.Paste")
		)
		(pad "56" smd rect
			(at -13.744 -0.25)
			(size 0.35 1.95)
			(layers "B.Cu" "B.Mask" "B.Paste")
		)
		(pad "57" smd rect
			(at -14 0)
			(size 0.35 1.45)
			(layers "F.Cu" "F.Mask" "F.Paste")
			(net "GND")
		)
		(pad "58" smd rect
			(at -14.244 -0.25)
			(size 0.35 1.95)
			(layers "B.Cu" "B.Mask" "B.Paste")
		)
		(pad "59" smd rect
			(at -14.5 0)
			(size 0.35 1.45)
			(layers "F.Cu" "F.Mask" "F.Paste")
		)
		(pad "60" smd rect
			(at -14.744 -0.25)
			(size 0.35 1.95)
			(layers "B.Cu" "B.Mask" "B.Paste")
		)
		(pad "61" smd rect
			(at -15 0)
			(size 0.35 1.45)
			(layers "F.Cu" "F.Mask" "F.Paste")
		)
		(pad "62" smd rect
			(at -15.244 -0.25)
			(size 0.35 1.95)
			(layers "B.Cu" "B.Mask" "B.Paste")
			(net "RX_GPS_CONN")
		)
		(pad "63" smd rect
			(at -15.5 0)
			(size 0.35 1.45)
			(layers "F.Cu" "F.Mask" "F.Paste")
		)
		(pad "64" smd rect
			(at -15.744 -0.25)
			(size 0.35 1.95)
			(layers "B.Cu" "B.Mask" "B.Paste")
			(net "TX_GPS_CONN")
		)
		(pad "65" smd rect
			(at -16 0)
			(size 0.35 1.45)
			(layers "F.Cu" "F.Mask" "F.Paste")
		)
		(pad "66" smd rect
			(at -16.244 -0.25)
			(size 0.35 1.95)
			(layers "B.Cu" "B.Mask" "B.Paste")
		)
		(pad "67" smd rect
			(at -16.5 0)
			(size 0.35 1.45)
			(layers "F.Cu" "F.Mask" "F.Paste")
			(net "NetJ1_67")
		)
		(pad "68" smd rect
			(at -16.744 -0.25)
			(size 0.35 1.95)
			(layers "B.Cu" "B.Mask" "B.Paste")
		)
		(pad "69" smd rect
			(at -17 0)
			(size 0.35 1.45)
			(layers "F.Cu" "F.Mask" "F.Paste")
		)
		(pad "70" smd rect
			(at -17.244 -0.25)
			(size 0.35 1.95)
			(layers "B.Cu" "B.Mask" "B.Paste")
			(net "+3V3")
		)
		(pad "71" smd rect
			(at -17.5 0)
			(size 0.35 1.45)
			(layers "F.Cu" "F.Mask" "F.Paste")
			(net "GND")
		)
		(pad "72" smd rect
			(at -17.744 -0.25)
			(size 0.35 1.95)
			(layers "B.Cu" "B.Mask" "B.Paste")
			(net "+3V3")
		)
		(pad "73" smd rect
			(at -18 0)
			(size 0.35 1.45)
			(layers "F.Cu" "F.Mask" "F.Paste")
			(net "GND")
		)
		(pad "74" smd rect
			(at -18.244 -0.25)
			(size 0.35 1.95)
			(layers "B.Cu" "B.Mask" "B.Paste")
			(net "+3V3")
		)
		(pad "75" smd rect
			(at -18.5 0)
			(size 0.35 1.45)
			(layers "F.Cu" "F.Mask" "F.Paste")
			(net "GND")
		)
	)
	(footprint "MyLibrary:r0402"
		(layer "F.Cu")
		(at 147.501105 93.6036 180)
		(property "Reference" "R1"
			(at 0.622205 1.177557 0)
			(unlocked yes)
			(layer "F.SilkS")
			(effects
				(font
					(size 0.635 0.635)
					(thickness 0.1778)
				)
			)
		)
		(property "Value" "0 ohm 0402"
			(at 2.907155 2.168983 180)
			(unlocked yes)
			(layer "F.SilkS")
			(hide yes)
			(effects
				(font
					(size 0.635 0.635)
					(thickness 0.1778)
				)
			)
		)
		(sheetname "01-M2_NEO-M9N_MODULE")
		(sheetfile "01-M2_NEO-M9N_MODULE.kicad_sch")
		(duplicate_pad_numbers_are_jumpers no)
		(fp_line
			(start 0.9906 0.5334)
			(end -0.9906 0.5334)
			(stroke
				(width 0.1778)
				(type solid)
			)
			(layer "F.SilkS")
		)
		(fp_line
			(start 0.9906 -0.5334)
			(end 0.9906 0.5334)
			(stroke
				(width 0.1778)
				(type solid)
			)
			(layer "F.SilkS")
		)
		(fp_line
			(start 0.9906 -0.5334)
			(end -0.9906 -0.5334)
			(stroke
				(width 0.1778)
				(type solid)
			)
			(layer "F.SilkS")
		)
		(fp_line
			(start -0.9906 -0.5334)
			(end -0.9906 0.5334)
			(stroke
				(width 0.1778)
				(type solid)
			)
			(layer "F.SilkS")
		)
		(pad "1" smd rect
			(at -0.5 0 180)
			(size 0.5 0.6)
			(layers "F.Cu" "F.Mask" "F.Paste")
			(net "VDD_USB")
		)
		(pad "2" smd rect
			(at 0.5 0 180)
			(size 0.5 0.6)
			(layers "F.Cu" "F.Mask" "F.Paste")
			(net "GND")
		)
	)
	(footprint "MyLibrary:c0402"
		(layer "F.Cu")
		(at 154.901105 111.2036 180)
		(property "Reference" "C2"
			(at -1.977795 -0.022443 0)
			(unlocked yes)
			(layer "F.SilkS")
			(effects
				(font
					(size 0.635 0.635)
					(thickness 0.1778)
				)
			)
		)
		(property "Value" "100nF 10V 0402"
			(at 5.700245 2.118183 180)
			(unlocked yes)
			(layer "F.SilkS")
			(hide yes)
			(effects
				(font
					(size 0.635 0.635)
					(thickness 0.1778)
				)
			)
		)
		(sheetname "01-M2_NEO-M9N_MODULE")
		(sheetfile "01-M2_NEO-M9N_MODULE.kicad_sch")
		(duplicate_pad_numbers_are_jumpers no)
		(fp_line
			(start 0.9906 0.4826)
			(end -0.9906 0.4826)
			(stroke
				(width 0.1778)
				(type solid)
			)
			(layer "F.SilkS")
		)
		(fp_line
			(start 0.9906 -0.4826)
			(end 0.9906 0.4826)
			(stroke
				(width 0.1778)
				(type solid)
			)
			(layer "F.SilkS")
		)
		(fp_line
			(start 0.9906 -0.4826)
			(end -0.9906 -0.4826)
			(stroke
				(width 0.1778)
				(type solid)
			)
			(layer "F.SilkS")
		)
		(fp_line
			(start -0.9906 -0.4826)
			(end -0.9906 0.4826)
			(stroke
				(width 0.1778)
				(type solid)
			)
			(layer "F.SilkS")
		)
		(pad "1" smd rect
			(at -0.5 0 180)
			(size 0.5 0.5)
			(layers "F.Cu" "F.Mask" "F.Paste")
			(net "GND")
		)
		(pad "2" smd rect
			(at 0.5 0 180)
			(size 0.5 0.5)
			(layers "F.Cu" "F.Mask" "F.Paste")
			(net "+3V3")
		)
	)
	(footprint "Vault:FP-LQG15HH_02-IPC_C"
		(layer "F.Cu")
		(at 141.801105 90.0036 180)
		(property "Reference" "L1"
			(at 1.822195 0.077557 0)
			(unlocked yes)
			(layer "F.SilkS")
			(effects
				(font
					(size 0.635 0.635)
					(thickness 0.1778)
				)
			)
		)
		(property "Value" "27nH 350mA 0.46ohm 0402"
			(at 12.962345 2.118183 180)
			(unlocked yes)
			(layer "F.SilkS")
			(hide yes)
			(effects
				(font
					(size 0.635 0.635)
					(thickness 0.1778)
				)
			)
		)
		(sheetname "01-M2_NEO-M9N_MODULE")
		(sheetfile "01-M2_NEO-M9N_MODULE.kicad_sch")
		(duplicate_pad_numbers_are_jumpers no)
		(fp_line
			(start 0.63624 0.675)
			(end -0.63624 0.675)
			(stroke
				(width 0.2)
				(type solid)
			)
			(layer "F.SilkS")
		)
		(fp_line
			(start 0.63624 -0.675)
			(end -0.63624 -0.675)
			(stroke
				(width 0.2)
				(type solid)
			)
			(layer "F.SilkS")
		)
		(fp_circle
			(center -0.8 1.3)
			(end -0.8 1.425)
			(stroke
				(width 0.25)
				(type solid)
			)
			(fill no)
			(layer "F.SilkS")
		)
		(fp_line
			(start 0.73624 0.375)
			(end -0.73624 0.375)
			(stroke
				(width 0.2)
				(type solid)
			)
			(layer "F.CrtYd")
		)
		(fp_line
			(start 0.73624 -0.375)
			(end 0.73624 0.375)
			(stroke
				(width 0.2)
				(type solid)
			)
			(layer "F.CrtYd")
		)
		(fp_line
			(start 0.73624 -0.375)
			(end -0.73624 -0.375)
			(stroke
				(width 0.2)
				(type solid)
			)
			(layer "F.CrtYd")
		)
		(fp_line
			(start -0.73624 -0.375)
			(end -0.73624 0.375)
			(stroke
				(width 0.2)
				(type solid)
			)
			(layer "F.CrtYd")
		)
		(fp_line
			(start 0.73624 0.375)
			(end -0.73624 0.375)
			(stroke
				(width 0.2)
				(type solid)
			)
			(layer "F.Fab")
		)
		(fp_line
			(start 0.73624 -0.375)
			(end 0.73624 0.375)
			(stroke
				(width 0.2)
				(type solid)
			)
			(layer "F.Fab")
		)
		(fp_line
			(start 0.73624 -0.375)
			(end -0.73624 -0.375)
			(stroke
				(width 0.2)
				(type solid)
			)
			(layer "F.Fab")
		)
		(fp_line
			(start 0.5 0)
			(end -0.5 0)
			(stroke
				(width 0.1)
				(type solid)
			)
			(layer "F.Fab")
		)
		(fp_line
			(start 0 -0.5)
			(end 0 0.5)
			(stroke
				(width 0.1)
				(type solid)
			)
			(layer "F.Fab")
		)
		(fp_line
			(start -0.73624 -0.375)
			(end -0.73624 0.375)
			(stroke
				(width 0.2)
				(type solid)
			)
			(layer "F.Fab")
		)
		(fp_text user "${REFERENCE}"
			(at 0.00001 0.29534 180)
			(unlocked yes)
			(layer "F.Fab")
			(effects
				(font
					(face "Arial")
					(size 0.63 0.63)
					(thickness 0.1)
				)
				(justify left bottom)
			)
		)
		(pad "1" smd rect
			(at -0.37856 0 180)
			(size 0.51535 0.47247)
			(layers "F.Cu" "F.Mask" "F.Paste")
			(net "NetC5_2")
			(solder_mask_margin 0)
			(solder_paste_margin 0)
		)
		(pad "2" smd rect
			(at 0.37857 0 180)
			(size 0.51535 0.47247)
			(layers "F.Cu" "F.Mask" "F.Paste")
			(net "RF_ANT")
			(solder_mask_margin 0)
			(solder_paste_margin 0)
		)
	)
)
